(kicad_pcb
	(version 20241229)
	(generator "pcbnew")
	(generator_version "9.0")
	(general
		(thickness 1.61)
		(legacy_teardrops no)
	)
	(paper "A3")
	(title_block
		(title "RDIMM DDR5 Tester")
		(date "2026-05-21")
		(rev "2.2.0")
		(company "Antmicro")
		(comment 9 "footprints 195-198 of 796")
	)
	(layers
		(0 "F.Cu" signal)
		(4 "In1.Cu" power)
		(6 "In2.Cu" mixed)
		(8 "In3.Cu" power)
		(10 "In4.Cu" mixed)
		(12 "In5.Cu" power)
		(14 "In6.Cu" mixed)
		(16 "In7.Cu" power)
		(18 "In8.Cu" power)
		(20 "In9.Cu" mixed)
		(22 "In10.Cu" power)
		(2 "B.Cu" signal)
		(9 "F.Adhes" user "F.Adhesive")
		(11 "B.Adhes" user "B.Adhesive")
		(13 "F.Paste" user)
		(15 "B.Paste" user)
		(5 "F.SilkS" user "F.Silkscreen")
		(7 "B.SilkS" user "B.Silkscreen")
		(1 "F.Mask" user)
		(3 "B.Mask" user)
		(17 "Dwgs.User" user "User.Drawings")
		(19 "Cmts.User" user "User.Comments")
		(21 "Eco1.User" user "User.Eco1")
		(23 "Eco2.User" user "User.Eco2")
		(25 "Edge.Cuts" user)
		(27 "Margin" user)
		(31 "F.CrtYd" user "F.Courtyard")
		(29 "B.CrtYd" user "B.Courtyard")
		(35 "F.Fab" user)
		(33 "B.Fab" user)
	)
	(footprint "antmicro-footprints:C_0402_1005Metric"
		(layer "F.Cu")
		(at 124.756 186.5875 -90)
		(descr "Capacitor SMD 0402")
		(tags "capacitor SMD 0402")
		(property "Reference" "C274"
			(at -0.9375 -1.469 90)
			(layer "F.SilkS")
			(effects
				(font
					(size 0.7 0.7)
					(thickness 0.15)
				)
				(justify right bottom)
			)
		)
		(property "Value" "C_100n_0402"
			(at -1.022927 2.155213 90)
			(layer "F.Fab")
			(effects
				(font
					(size 0.7 0.7)
					(thickness 0.15)
				)
				(justify right bottom)
			)
		)
		(property "Datasheet" "https://www.murata.com/products/productdetail?partno=GRM155R61H104KE14%23"
			(at 0 0 270)
			(layer "F.Fab")
			(hide yes)
			(effects
				(font
					(size 1.27 1.27)
					(thickness 0.15)
				)
			)
		)
		(property "MPN" "GRM155R61H104KE14D"
			(at 0 0 270)
			(unlocked yes)
			(layer "F.Fab")
			(hide yes)
			(effects
				(font
					(size 1 1)
					(thickness 0.15)
				)
			)
		)
		(property "Manufacturer" "Murata"
			(at 0 0 270)
			(unlocked yes)
			(layer "F.Fab")
			(hide yes)
			(effects
				(font
					(size 1 1)
					(thickness 0.15)
				)
			)
		)
		(property "License" "Apache-2.0"
			(at 0 0 270)
			(unlocked yes)
			(layer "F.Fab")
			(hide yes)
			(effects
				(font
					(size 1 1)
					(thickness 0.15)
				)
			)
		)
		(property "Author" "Antmicro"
			(at 0 0 270)
			(unlocked yes)
			(layer "F.Fab")
			(hide yes)
			(effects
				(font
					(size 1 1)
					(thickness 0.15)
				)
			)
		)
		(property "Val" "100n"
			(at 0 0 270)
			(unlocked yes)
			(layer "F.Fab")
			(hide yes)
			(effects
				(font
					(size 1 1)
					(thickness 0.15)
				)
			)
		)
		(property "Voltage" "50V"
			(at 0 0 270)
			(unlocked yes)
			(layer "F.Fab")
			(hide yes)
			(effects
				(font
					(size 1 1)
					(thickness 0.15)
				)
			)
		)
		(property "Dielectric" "X5R"
			(at 0 0 270)
			(unlocked yes)
			(layer "F.Fab")
			(hide yes)
			(effects
				(font
					(size 1 1)
					(thickness 0.15)
				)
			)
		)
		(property "Public" ""
			(at 0 0 270)
			(unlocked yes)
			(layer "F.Fab")
			(hide yes)
			(effects
				(font
					(size 1 1)
					(thickness 0.15)
				)
			)
		)
		(sheetname "/HDMI + SD Card/")
		(sheetfile "hdmi-sd-card.kicad_sch")
		(attr smd)
		(fp_rect
			(start -0.925 -0.47)
			(end 0.925 0.47)
			(stroke
				(width 0.05)
				(type default)
			)
			(fill no)
			(layer "F.CrtYd")
		)
		(fp_line
			(start -0.494 0.248)
			(end -0.494 -0.25)
			(stroke
				(width 0.15)
				(type solid)
			)
			(layer "F.Fab")
		)
		(fp_line
			(start 0.504 0.248)
			(end -0.494 0.248)
			(stroke
				(width 0.15)
				(type solid)
			)
			(layer "F.Fab")
		)
		(fp_line
			(start -0.494 -0.25)
			(end 0.504 -0.25)
			(stroke
				(width 0.15)
				(type solid)
			)
			(layer "F.Fab")
		)
		(fp_line
			(start 0.504 -0.25)
			(end 0.504 0.248)
			(stroke
				(width 0.15)
				(type solid)
			)
			(layer "F.Fab")
		)
		(fp_text user "License: Apache-2.0"
			(at -0.939 5.799 270)
			(layer "F.Fab")
			(effects
				(font
					(size 0.7 0.7)
					(thickness 0.15)
				)
				(justify left bottom)
			)
		)
		(fp_text user "Author: Antmicro"
			(at -0.939 3.399 270)
			(layer "F.Fab")
			(effects
				(font
					(size 0.7 0.7)
					(thickness 0.15)
				)
				(justify left bottom)
			)
		)
		(fp_text user "${REFERENCE}"
			(at -0.939 4.599 270)
			(layer "F.Fab")
			(effects
				(font
					(size 0.7 0.7)
					(thickness 0.15)
				)
				(justify left bottom)
			)
		)
		(pad "1" smd roundrect
			(at -0.48 0 270)
			(size 0.59 0.64)
			(layers "F.Cu" "F.Mask" "F.Paste")
			(roundrect_rratio 0.25)
			(net 151 "+3V3")
			(pintype "passive")
		)
		(pad "2" smd roundrect
			(at 0.48 0 270)
			(size 0.59 0.64)
			(layers "F.Cu" "F.Mask" "F.Paste")
			(roundrect_rratio 0.25)
			(net 1 "GND")
			(pintype "passive")
		)
	)
	(footprint "antmicro-footprints:R_0402_1005Metric"
		(layer "F.Cu")
		(at 123.056 174.9375 -90)
		(descr "Resistor SMD 0402")
		(tags "resistor SMD 0402")
		(property "Reference" "R76"
			(at -1.1625 -1.494 90)
			(layer "F.SilkS")
			(effects
				(font
					(size 0.7 0.7)
					(thickness 0.15)
				)
				(justify right bottom)
			)
		)
		(property "Value" "R_6k49_0402"
			(at -1.011843 1.772047 90)
			(layer "F.Fab")
			(effects
				(font
					(size 0.7 0.7)
					(thickness 0.15)
				)
				(justify right bottom)
			)
		)
		(property "Datasheet" "https://www.farnell.com/datasheets/3795017.pdf"
			(at 0 0 270)
			(layer "F.Fab")
			(hide yes)
			(effects
				(font
					(size 1.27 1.27)
					(thickness 0.15)
				)
			)
		)
		(property "MPN" "RMCF0402FT6K49"
			(at 0 0 270)
			(unlocked yes)
			(layer "F.Fab")
			(hide yes)
			(effects
				(font
					(size 1 1)
					(thickness 0.15)
				)
			)
		)
		(property "Manufacturer" "Stackpole Electronics"
			(at 0 0 270)
			(unlocked yes)
			(layer "F.Fab")
			(hide yes)
			(effects
				(font
					(size 1 1)
					(thickness 0.15)
				)
			)
		)
		(property "License" "Apache-2.0"
			(at 0 0 270)
			(unlocked yes)
			(layer "F.Fab")
			(hide yes)
			(effects
				(font
					(size 1 1)
					(thickness 0.15)
				)
			)
		)
		(property "Author" "Antmicro"
			(at 0 0 270)
			(unlocked yes)
			(layer "F.Fab")
			(hide yes)
			(effects
				(font
					(size 1 1)
					(thickness 0.15)
				)
			)
		)
		(property "Val" "6k49"
			(at 0 0 270)
			(unlocked yes)
			(layer "F.Fab")
			(hide yes)
			(effects
				(font
					(size 1 1)
					(thickness 0.15)
				)
			)
		)
		(property "Tolerance" "1%"
			(at 0 0 270)
			(unlocked yes)
			(layer "F.Fab")
			(hide yes)
			(effects
				(font
					(size 1 1)
					(thickness 0.15)
				)
			)
		)
		(sheetname "/HDMI + SD Card/")
		(sheetfile "hdmi-sd-card.kicad_sch")
		(attr smd)
		(fp_rect
			(start -0.925 -0.47)
			(end 0.925 0.47)
			(stroke
				(width 0.05)
				(type default)
			)
			(fill no)
			(layer "F.CrtYd")
		)
		(fp_rect
			(start -0.5 -0.25)
			(end 0.5 0.25)
			(stroke
				(width 0.15)
				(type solid)
			)
			(fill no)
			(layer "F.Fab")
		)
		(fp_text user "License: Apache-2.0"
			(at -0.95 5.169 270)
			(layer "F.Fab")
			(effects
				(font
					(size 0.7 0.7)
					(thickness 0.15)
				)
				(justify left bottom)
			)
		)
		(fp_text user "Author: Antmicro"
			(at -0.95 4.169 270)
			(layer "F.Fab")
			(effects
				(font
					(size 0.7 0.7)
					(thickness 0.15)
				)
				(justify left bottom)
			)
		)
		(fp_text user "${REFERENCE}"
			(at -0.95 3.168 270)
			(layer "F.Fab")
			(effects
				(font
					(size 0.7 0.7)
					(thickness 0.15)
				)
				(justify left bottom)
			)
		)
		(pad "1" smd roundrect
			(at -0.48 0 270)
			(size 0.59 0.64)
			(layers "F.Cu" "F.Mask" "F.Paste")
			(roundrect_rratio 0.25)
			(net 1 "GND")
			(pintype "passive")
		)
		(pad "2" smd roundrect
			(at 0.48 0 270)
			(size 0.59 0.64)
			(layers "F.Cu" "F.Mask" "F.Paste")
			(roundrect_rratio 0.25)
			(net 709 "Net-(U38-VSADJ)")
			(pintype "passive")
		)
	)
	(footprint "antmicro-footprints:LED_0603_1608Metric_G"
		(layer "F.Cu")
		(at 113.405 102.225 90)
		(descr "LED SMD 0603 Green")
		(tags "LED SMD 0603 Green")
		(property "Reference" "D4"
			(at -2.575 -0.305 90)
			(layer "F.SilkS")
			(hide yes)
			(effects
				(font
					(size 0.7 0.7)
					(thickness 0.15)
				)
				(justify left bottom)
			)
		)
		(property "Value" "LED_G_0603_KP-1608CGCK"
			(at -0.001 1.599 90)
			(layer "F.Fab")
			(effects
				(font
					(size 0.7 0.7)
					(thickness 0.15)
				)
				(justify left bottom)
			)
		)
		(property "Datasheet" "http://www.kingbright.com/attachments/file/psearch//000/00/00/KP-1608CGCK(Ver.23B).pdf"
			(at 0 0 90)
			(layer "F.Fab")
			(hide yes)
			(effects
				(font
					(size 1.27 1.27)
					(thickness 0.15)
				)
			)
		)
		(property "MPN" "KP-1608CGCK"
			(at 0 0 90)
			(unlocked yes)
			(layer "F.Fab")
			(hide yes)
			(effects
				(font
					(size 1 1)
					(thickness 0.15)
				)
			)
		)
		(property "Manufacturer" "Kingbright"
			(at 0 0 90)
			(unlocked yes)
			(layer "F.Fab")
			(hide yes)
			(effects
				(font
					(size 1 1)
					(thickness 0.15)
				)
			)
		)
		(property "Author" "Antmicro"
			(at 0 0 90)
			(unlocked yes)
			(layer "F.Fab")
			(hide yes)
			(effects
				(font
					(size 1 1)
					(thickness 0.15)
				)
			)
		)
		(property "License" "Apache-2.0"
			(at 0 0 90)
			(unlocked yes)
			(layer "F.Fab")
			(hide yes)
			(effects
				(font
					(size 1 1)
					(thickness 0.15)
				)
			)
		)
		(property "Color" "Green"
			(at 0 0 90)
			(unlocked yes)
			(layer "F.Fab")
			(hide yes)
			(effects
				(font
					(size 1 1)
					(thickness 0.15)
				)
			)
		)
		(sheetname "/FPGA banks HD/")
		(sheetfile "fpga-hd-banks.kicad_sch")
		(attr smd)
		(fp_line
			(start 0.22 -0.35)
			(end -0.22 -0.35)
			(stroke
				(width 0.15)
				(type solid)
			)
			(layer "F.SilkS")
		)
		(fp_line
			(start -1.18 -0.319)
			(end -1.18 0.321)
			(stroke
				(width 0.15)
				(type solid)
			)
			(layer "F.SilkS")
		)
		(fp_line
			(start 0.105328 0.001008)
			(end 0.24 0.001)
			(stroke
				(width 0.1)
				(type solid)
			)
			(layer "F.SilkS")
		)
		(fp_line
			(start -0.094672 0.001008)
			(end 0.105328 -0.198992)
			(stroke
				(width 0.1)
				(type solid)
			)
			(layer "F.SilkS")
		)
		(fp_line
			(start -0.094672 0.001008)
			(end -0.24 0.001008)
			(stroke
				(width 0.1)
				(type solid)
			)
			(layer "F.SilkS")
		)
		(fp_line
			(start 0.105328 0.201008)
			(end 0.105328 -0.198992)
			(stroke
				(width 0.1)
				(type solid)
			)
			(layer "F.SilkS")
		)
		(fp_line
			(start 0.105328 0.201008)
			(end -0.094672 0.001008)
			(stroke
				(width 0.1)
				(type solid)
			)
			(layer "F.SilkS")
		)
		(fp_line
			(start -0.094672 0.201008)
			(end -0.094672 -0.198992)
			(stroke
				(width 0.1)
				(type solid)
			)
			(layer "F.SilkS")
		)
		(fp_line
			(start 0.22 0.35)
			(end -0.22 0.35)
			(stroke
				(width 0.15)
				(type solid)
			)
			(layer "F.SilkS")
		)
		(fp_rect
			(start 1.25 0.65)
			(end -1.25 -0.65)
			(stroke
				(width 0.05)
				(type solid)
			)
			(fill no)
			(layer "F.CrtYd")
		)
		(fp_line
			(start 0.201 -0.202)
			(end -0.101 0)
			(stroke
				(width 0.15)
				(type solid)
			)
			(layer "F.Fab")
		)
		(fp_line
			(start -0.199 -0.202)
			(end -0.199 0.1)
			(stroke
				(width 0.15)
				(type solid)
			)
			(layer "F.Fab")
		)
		(fp_line
			(start 0.599 0)
			(end 0.201 0)
			(stroke
				(width 0.15)
				(type solid)
			)
			(layer "F.Fab")
		)
		(fp_line
			(start 0.201 0)
			(end 0.201 -0.202)
			(stroke
				(width 0.15)
				(type solid)
			)
			(layer "F.Fab")
		)
		(fp_line
			(start -0.101 0)
			(end 0.201 0.2)
			(stroke
				(width 0.15)
				(type solid)
			)
			(layer "F.Fab")
		)
		(fp_line
			(start -0.199 0)
			(end -0.597 0)
			(stroke
				(width 0.15)
				(type solid)
			)
			(layer "F.Fab")
		)
		(fp_line
			(start 0.201 0.2)
			(end 0.201 0)
			(stroke
				(width 0.15)
				(type solid)
			)
			(layer "F.Fab")
		)
		(fp_line
			(start -0.199 0.2)
			(end -0.199 0.1)
			(stroke
				(width 0.15)
				(type solid)
			)
			(layer "F.Fab")
		)
		(fp_rect
			(start 0.848 0.4)
			(end -0.85 -0.402)
			(stroke
				(width 0.15)
				(type solid)
			)
			(fill no)
			(layer "F.Fab")
		)
		(fp_text user "Author: Antmicro"
			(at -1.4224 4.799 90)
			(layer "F.Fab")
			(effects
				(font
					(size 0.7 0.7)
					(thickness 0.15)
				)
				(justify left bottom)
			)
		)
		(fp_text user "License: Apache-2.0"
			(at -1.4224 3.599 90)
			(layer "F.Fab")
			(effects
				(font
					(size 0.7 0.7)
					(thickness 0.15)
				)
				(justify left bottom)
			)
		)
		(fp_text user "${REFERENCE}"
			(at -1.4224 5.999 90)
			(layer "F.Fab")
			(effects
				(font
					(size 0.7 0.7)
					(thickness 0.15)
				)
				(justify left bottom)
			)
		)
		(pad "1" smd roundrect
			(at -0.7 0 270)
			(size 0.8 1)
			(layers "F.Cu" "F.Mask" "F.Paste")
			(roundrect_rratio 0.2)
			(net 151 "+3V3")
			(pinfunction "C")
			(pintype "passive")
		)
		(pad "2" smd roundrect
			(at 0.7 0 270)
			(size 0.8 1)
			(layers "F.Cu" "F.Mask" "F.Paste")
			(roundrect_rratio 0.2)
			(net 32 "Net-(D4-A)")
			(pinfunction "A")
			(pintype "passive")
		)
	)
	(footprint "antmicro-footprints:Vishay_PowerPAK_1212-8_Single"
		(layer "F.Cu")
		(at 247.1255 126.55 90)
		(descr "PowerPAK 1212-8 Single")
		(tags "Vishay PowerPAK 1212-8 Single")
		(property "Reference" "Q12"
			(at -2.95 -0.2255 180)
			(layer "F.SilkS")
			(effects
				(font
					(size 0.7 0.7)
					(thickness 0.15)
				)
				(justify left bottom)
			)
		)
		(property "Value" "SI7613DN-T1-GE3"
			(at 0 2.7 90)
			(layer "F.Fab")
			(effects
				(font
					(size 0.7 0.7)
					(thickness 0.15)
				)
				(justify left bottom)
			)
		)
		(property "Datasheet" "https://www.vishay.com/docs/64809/si7613dn.pdf"
			(at 0 0 90)
			(layer "F.Fab")
			(hide yes)
			(effects
				(font
					(size 1.27 1.27)
					(thickness 0.15)
				)
			)
		)
		(property "MPN" "SI7613DN-T1-GE3"
			(at 0 0 90)
			(unlocked yes)
			(layer "F.Fab")
			(hide yes)
			(effects
				(font
					(size 1 1)
					(thickness 0.15)
				)
			)
		)
		(property "Manufacturer" "Vishay"
			(at 0 0 90)
			(unlocked yes)
			(layer "F.Fab")
			(hide yes)
			(effects
				(font
					(size 1 1)
					(thickness 0.15)
				)
			)
		)
		(property "Author" "Antmicro"
			(at 0 0 90)
			(unlocked yes)
			(layer "F.Fab")
			(hide yes)
			(effects
				(font
					(size 1 1)
					(thickness 0.15)
				)
			)
		)
		(property "License" "Apache-2.0"
			(at 0 0 90)
			(unlocked yes)
			(layer "F.Fab")
			(hide yes)
			(effects
				(font
					(size 1 1)
					(thickness 0.15)
				)
			)
		)
		(sheetname "/Supply/")
		(sheetfile "supply.kicad_sch")
		(attr smd)
		(fp_line
			(start 1.648 -1.651)
			(end 1.648 -1.317)
			(stroke
				(width 0.15)
				(type solid)
			)
			(layer "F.SilkS")
		)
		(fp_line
			(start -1.651 -1.651)
			(end 1.648 -1.651)
			(stroke
				(width 0.15)
				(type solid)
			)
			(layer "F.SilkS")
		)
		(fp_line
			(start -1.651 -1.651)
			(end -1.651 -1.317)
			(stroke
				(width 0.15)
				(type solid)
			)
			(layer "F.SilkS")
		)
		(fp_line
			(start 1.634 1.3)
			(end 1.634 1.634)
			(stroke
				(width 0.15)
				(type solid)
			)
			(layer "F.SilkS")
		)
		(fp_line
			(start -1.635 1.3)
			(end -1.635 1.634)
			(stroke
				(width 0.15)
				(type solid)
			)
			(layer "F.SilkS")
		)
		(fp_line
			(start -1.635 1.634)
			(end 1.634 1.634)
			(stroke
				(width 0.15)
				(type solid)
			)
			(layer "F.SilkS")
		)
		(fp_circle
			(center -1.9 -1.4)
			(end -1.85 -1.4)
			(stroke
				(width 0.15)
				(type solid)
			)
			(fill yes)
			(layer "F.SilkS")
		)
		(fp_rect
			(start -2 -1.8)
			(end 2 1.798)
			(stroke
				(width 0.05)
				(type solid)
			)
			(fill no)
			(layer "F.CrtYd")
		)
		(fp_line
			(start -1.6425 -1.4175)
			(end -1.4175 -1.6425)
			(stroke
				(width 0.15)
				(type solid)
			)
			(layer "F.Fab")
		)
		(fp_rect
			(start -1.651 -1.651)
			(end 1.648 1.648)
			(stroke
				(width 0.15)
				(type solid)
			)
			(fill no)
			(layer "F.Fab")
		)
		(fp_text user "Author: Antmicro"
			(at -8 5.9 90)
			(layer "F.Fab")
			(effects
				(font
					(size 0.7 0.7)
					(thickness 0.15)
				)
				(justify left bottom)
			)
		)
		(fp_text user "${REFERENCE}"
			(at -8 4.7 90)
			(layer "F.Fab")
			(effects
				(font
					(size 0.7 0.7)
					(thickness 0.15)
				)
				(justify left bottom)
			)
		)
		(fp_text user "License: Apache-2.0"
			(at -8 7.1 90)
			(layer "F.Fab")
			(effects
				(font
					(size 0.7 0.7)
					(thickness 0.15)
				)
				(justify left bottom)
			)
		)
		(pad "1" smd rect
			(at -1.436 -0.99 90)
			(size 0.99 0.405)
			(layers "F.Cu" "F.Mask" "F.Paste")
			(net 35 "VDC")
			(pinfunction "S")
			(pintype "passive")
		)
		(pad "2" smd rect
			(at -1.436 -0.332 90)
			(size 0.99 0.405)
			(layers "F.Cu" "F.Mask" "F.Paste")
			(net 35 "VDC")
			(pinfunction "S")
			(pintype "passive")
		)
		(pad "3" smd rect
			(at -1.436 0.33 90)
			(size 0.99 0.405)
			(layers "F.Cu" "F.Mask" "F.Paste")
			(net 35 "VDC")
			(pinfunction "S")
			(pintype "passive")
		)
		(pad "4" smd rect
			(at -1.436 0.988 90)
			(size 0.99 0.405)
			(layers "F.Cu" "F.Mask" "F.Paste")
			(net 284 "Net-(Q12-G)")
			(pinfunction "G")
			(pintype "passive")
		)
		(pad "5" smd custom
			(at 0.557 0 90)
			(size 1.725 2.235)
			(layers "F.Cu" "F.Mask" "F.Paste")
			(net 323 "/Supply/12V_aux_fused")
			(pinfunction "D")
			(pintype "passive")
			(zone_connect 2)
			(options
				(clearance outline)
				(anchor rect)
			)
			(primitives
				(gr_poly
					(pts
						(xy 0.8625 0.1275) (xy 0.8625 -0.1275) (xy 1.3725 -0.1275) (xy 1.3725 -0.5325) (xy 0.8625 -0.5325)
						(xy 0.8625 -0.7875) (xy 1.3725 -0.7875) (xy 1.3725 -1.195) (xy 0.6125 -1.195) (xy 0.6125 1.195)
						(xy 1.3725 1.195) (xy 1.3725 0.7875) (xy 0.8625 0.7875) (xy 0.8625 0.5325) (xy 1.3725 0.5325)
						(xy 1.3725 0.1275)
					)
					(width 0)
					(fill yes)
				)
			)
		)
	)
)
